(kicad_pcb
	(version 20260206)
	(generator "pcbnew")
	(generator_version "10.0")
	(general
		(thickness 1.6)
		(legacy_teardrops no)
	)
	(paper "A4")
	(title_block
		(title "Bryce Canyon_SCC_16316-1_OCP.brd")
		(comment 1 "Bryce Canyon / footprints 1551-1558 of 1561")
	)
	(layers
		(0 "F.Cu" signal "TOP")
		(4 "In1.Cu" signal "L2GND")
		(6 "In2.Cu" signal "L3")
		(8 "In3.Cu" signal "L4VCC")
		(10 "In4.Cu" signal "L5VCC")
		(12 "In5.Cu" signal "L6")
		(14 "In6.Cu" signal "L7GND")
		(2 "B.Cu" signal "BOTTOM")
		(9 "F.Adhes" user "F.Adhesive")
		(11 "B.Adhes" user "B.Adhesive")
		(13 "F.Paste" user "Package Geometry/Pastemask Top")
		(15 "B.Paste" user "Package Geometry/Pastemask Bottom")
		(5 "F.SilkS" user "Ref Des/Silkscreen Top")
		(7 "B.SilkS" user "Ref Des/Silkscreen Bottom")
		(1 "F.Mask" user "Board Geometry/Soldermask Top")
		(3 "B.Mask" user "Board Geometry/Soldermask Bottom")
		(17 "Dwgs.User" user "User.Drawings")
		(19 "Cmts.User" user "User.Comments")
		(21 "Eco1.User" user "User.Eco1")
		(23 "Eco2.User" user "User.Eco2")
		(25 "Edge.Cuts" user "Board Geometry/Outline")
		(27 "Margin" user)
		(31 "F.CrtYd" user "Package Geometry/Place Bound Top")
		(29 "B.CrtYd" user "Package Geometry/Place Bound Bottom")
		(35 "F.Fab" user "Ref Des/Assembly Top")
		(33 "B.Fab" user "Ref Des/Assembly Bottom")
	)
	(footprint ""
		(layer "B.Cu")
		(at 118.7704 -59.4487)
		(property "Reference" "C513"
			(at 0 0 0)
			(layer "B.SilkS")
			(hide yes)
			(effects
				(font
					(size 1.27 1.27)
				)
				(justify mirror)
			)
		)
		(property "Value" "SCD1U6D3V1KX-GP"
			(at 2.8321 -1.7399 0)
			(unlocked yes)
			(layer "B.Fab")
			(hide yes)
			(effects
				(font
					(size 1.016 1.016)
					(thickness 0.1524)
				)
				(justify mirror)
			)
		)
		(property "Device Type" "C0201H13"
			(at 2.8321 -3.2639 0)
			(unlocked yes)
			(layer "B.Fab")
			(hide yes)
			(effects
				(font
					(size 1.016 1.016)
					(thickness 0.1524)
				)
				(justify mirror)
			)
		)
		(duplicate_pad_numbers_are_jumpers no)
		(fp_rect
			(start 0.2794 0.6477)
			(end -0.2794 -0.6477)
			(stroke
				(width 0)
				(type default)
			)
			(fill no)
			(layer "B.CrtYd")
		)
		(fp_rect
			(start 0.2794 0.6477)
			(end -0.2794 -0.6477)
			(stroke
				(width 0)
				(type default)
			)
			(fill no)
			(layer "B.Fab")
		)
		(pad "1" smd custom
			(at 0 -0.2794 180)
			(size 0.0762 0.0762)
			(layers "B.Cu" "B.Mask" "B.Paste")
			(net "GB_VDDA")
			(options
				(clearance outline)
				(anchor circle)
			)
			(primitives
				(gr_poly
					(pts
						(arc
							(start 0.1524 0.127)
							(mid 0.137521 0.162921)
							(end 0.1016 0.1778)
						)
						(arc
							(start -0.1016 0.1778)
							(mid -0.137521 0.162921)
							(end -0.1524 0.127)
						)
						(arc
							(start -0.1524 -0.127)
							(mid -0.137521 -0.162921)
							(end -0.1016 -0.1778)
						)
						(arc
							(start 0.1016 -0.1778)
							(mid 0.137521 -0.162921)
							(end 0.1524 -0.127)
						)
					)
					(width 0)
					(fill yes)
				)
			)
		)
		(pad "2" smd custom
			(at 0 0.2794 180)
			(size 0.0762 0.0762)
			(layers "B.Cu" "B.Mask" "B.Paste")
			(net "GND")
			(options
				(clearance outline)
				(anchor circle)
			)
			(primitives
				(gr_poly
					(pts
						(arc
							(start 0.1524 0.127)
							(mid 0.137521 0.162921)
							(end 0.1016 0.1778)
						)
						(arc
							(start -0.1016 0.1778)
							(mid -0.137521 0.162921)
							(end -0.1524 0.127)
						)
						(arc
							(start -0.1524 -0.127)
							(mid -0.137521 -0.162921)
							(end -0.1016 -0.1778)
						)
						(arc
							(start 0.1016 -0.1778)
							(mid 0.137521 -0.162921)
							(end 0.1524 -0.127)
						)
					)
					(width 0)
					(fill yes)
				)
			)
		)
	)
	(footprint ""
		(layer "B.Cu")
		(at 163.2966 -33.2994 90)
		(property "Reference" "C373"
			(at 0 0 90)
			(layer "B.SilkS")
			(hide yes)
			(effects
				(font
					(size 1.27 1.27)
				)
				(justify mirror)
			)
		)
		(property "Value" "SC1U16V2KX-7-GP"
			(at -1.7526 -1.6002 90)
			(unlocked yes)
			(layer "B.Fab")
			(hide yes)
			(effects
				(font
					(size 1.016 1.016)
					(thickness 0.1524)
				)
				(justify mirror)
			)
		)
		(property "Device Type" "C402-TO0D2H24"
			(at -1.7526 -3.1242 90)
			(unlocked yes)
			(layer "B.Fab")
			(hide yes)
			(effects
				(font
					(size 1.016 1.016)
					(thickness 0.1524)
				)
				(justify mirror)
			)
		)
		(duplicate_pad_numbers_are_jumpers no)
		(fp_rect
			(start 0.4826 0.889)
			(end -0.4826 -0.889)
			(stroke
				(width 0)
				(type default)
			)
			(fill no)
			(layer "B.CrtYd")
		)
		(fp_rect
			(start 0.4826 0.889)
			(end -0.4826 -0.889)
			(stroke
				(width 0)
				(type default)
			)
			(fill no)
			(layer "B.Fab")
		)
		(pad "1" smd custom
			(at 0 -0.4572 270)
			(size 0.1524 0.1524)
			(layers "B.Cu" "B.Mask" "B.Paste")
			(net "SAS0_VDDH")
			(options
				(clearance outline)
				(anchor circle)
			)
			(primitives
				(gr_poly
					(pts
						(arc
							(start -0.254 -0.3048)
							(mid -0.325842 -0.275042)
							(end -0.3556 -0.2032)
						)
						(arc
							(start -0.3556 0.2032)
							(mid -0.325842 0.275042)
							(end -0.254 0.3048)
						)
						(arc
							(start 0.254 0.3048)
							(mid 0.325842 0.275042)
							(end 0.3556 0.2032)
						)
						(arc
							(start 0.3556 -0.2032)
							(mid 0.325842 -0.275042)
							(end 0.254 -0.3048)
						)
					)
					(width 0)
					(fill yes)
				)
			)
		)
		(pad "2" smd custom
			(at 0 0.4572 270)
			(size 0.1524 0.1524)
			(layers "B.Cu" "B.Mask" "B.Paste")
			(net "GND")
			(options
				(clearance outline)
				(anchor circle)
			)
			(primitives
				(gr_poly
					(pts
						(arc
							(start -0.254 -0.3048)
							(mid -0.325842 -0.275042)
							(end -0.3556 -0.2032)
						)
						(arc
							(start -0.3556 0.2032)
							(mid -0.325842 0.275042)
							(end -0.254 0.3048)
						)
						(arc
							(start 0.254 0.3048)
							(mid 0.325842 0.275042)
							(end 0.3556 0.2032)
						)
						(arc
							(start 0.3556 -0.2032)
							(mid 0.325842 -0.275042)
							(end 0.254 -0.3048)
						)
					)
					(width 0)
					(fill yes)
				)
			)
		)
	)
	(footprint ""
		(layer "B.Cu")
		(at 159.1056 -50.419)
		(property "Reference" "TP79"
			(at 0 0 0)
			(layer "B.SilkS")
			(hide yes)
			(effects
				(font
					(size 1.27 1.27)
				)
				(justify mirror)
			)
		)
		(property "Value" "TPAD28-2-GP"
			(at 0.0127 -1.6637 0)
			(unlocked yes)
			(layer "B.Fab")
			(hide yes)
			(effects
				(font
					(size 1.016 1.016)
					(thickness 0.1524)
				)
				(justify mirror)
			)
		)
		(property "Device Type" "TPAD28"
			(at 0.0127 -3.1877 0)
			(unlocked yes)
			(layer "B.Fab")
			(hide yes)
			(effects
				(font
					(size 1.016 1.016)
					(thickness 0.1524)
				)
				(justify mirror)
			)
		)
		(duplicate_pad_numbers_are_jumpers no)
		(fp_poly
			(pts
				(arc
					(start 0.3556 0)
					(mid -0.3556 0)
					(end 0.3556 0)
				)
			)
			(stroke
				(width 0)
				(type default)
			)
			(fill no)
			(layer "B.CrtYd")
		)
		(fp_poly
			(pts
				(arc
					(start 0.6096 0)
					(mid -0.6096 0)
					(end 0.6096 0)
				)
			)
			(stroke
				(width 0)
				(type default)
			)
			(fill no)
			(layer "B.Fab")
		)
		(pad "1" smd circle
			(at 0 0 180)
			(size 0.7112 0.7112)
			(layers "B.Cu" "B.Mask" "B.Paste")
			(net "SIO_CLK_0")
		)
	)
	(footprint ""
		(layer "B.Cu")
		(at 160.401 -27.178 180)
		(property "Reference" "R282"
			(at 0 0 0)
			(layer "B.SilkS")
			(hide yes)
			(effects
				(font
					(size 1.27 1.27)
				)
				(justify mirror)
			)
		)
		(property "Value" "10R2F-L-GP"
			(at -0.064008 -3.993896 180)
			(unlocked yes)
			(layer "B.Fab")
			(hide yes)
			(effects
				(font
					(size 1.016 1.016)
					(thickness 0.1524)
				)
				(justify mirror)
			)
		)
		(property "Device Type" "R402H14"
			(at -0.064008 -5.517896 180)
			(unlocked yes)
			(layer "B.Fab")
			(hide yes)
			(effects
				(font
					(size 1.016 1.016)
					(thickness 0.1524)
				)
				(justify mirror)
			)
		)
		(duplicate_pad_numbers_are_jumpers no)
		(fp_line
			(start 0.508 -0.9398)
			(end 0.508 0.9398)
			(stroke
				(width 0.1524)
				(type default)
			)
			(layer "B.SilkS")
		)
		(fp_line
			(start -0.508 -0.9398)
			(end 0.508 -0.9398)
			(stroke
				(width 0.1524)
				(type default)
			)
			(layer "B.SilkS")
		)
		(fp_rect
			(start 0.508 0.9398)
			(end -0.508 -0.9398)
			(stroke
				(width 0)
				(type default)
			)
			(fill no)
			(layer "B.CrtYd")
		)
		(fp_rect
			(start 0.508 0.9398)
			(end -0.508 -0.9398)
			(stroke
				(width 0)
				(type default)
			)
			(fill no)
			(layer "B.Fab")
		)
		(pad "1" smd custom
			(at 0 -0.4445)
			(size 0.1397 0.1397)
			(layers "B.Cu" "B.Mask" "B.Paste")
			(net "P1V8_C")
			(options
				(clearance outline)
				(anchor circle)
			)
			(primitives
				(gr_poly
					(pts
						(arc
							(start -0.1778 0.2794)
							(mid -0.249642 0.249642)
							(end -0.2794 0.1778)
						)
						(arc
							(start -0.2794 -0.1778)
							(mid -0.249642 -0.249642)
							(end -0.1778 -0.2794)
						)
						(arc
							(start 0.1778 -0.2794)
							(mid 0.249642 -0.249642)
							(end 0.2794 -0.1778)
						)
						(arc
							(start 0.2794 0.1778)
							(mid 0.249642 0.249642)
							(end 0.1778 0.2794)
						)
					)
					(width 0)
					(fill yes)
				)
			)
		)
		(pad "2" smd custom
			(at 0 0.4445)
			(size 0.1397 0.1397)
			(layers "B.Cu" "B.Mask" "B.Paste")
			(net "SAS0_VDDH")
			(options
				(clearance outline)
				(anchor circle)
			)
			(primitives
				(gr_poly
					(pts
						(arc
							(start -0.1778 0.2794)
							(mid -0.249642 0.249642)
							(end -0.2794 0.1778)
						)
						(arc
							(start -0.2794 -0.1778)
							(mid -0.249642 -0.249642)
							(end -0.1778 -0.2794)
						)
						(arc
							(start 0.1778 -0.2794)
							(mid 0.249642 -0.249642)
							(end 0.2794 -0.1778)
						)
						(arc
							(start 0.2794 0.1778)
							(mid 0.249642 0.249642)
							(end 0.1778 0.2794)
						)
					)
					(width 0)
					(fill yes)
				)
			)
		)
	)
	(footprint ""
		(layer "B.Cu")
		(at 179.187348 -49.62271 -90)
		(property "Reference" "C498"
			(at 0 0 90)
			(layer "B.SilkS")
			(hide yes)
			(effects
				(font
					(size 1.27 1.27)
				)
				(justify mirror)
			)
		)
		(property "Value" "SC1KP50V2KX-1GP"
			(at -1.1811 -2.7051 270)
			(unlocked yes)
			(layer "B.Fab")
			(hide yes)
			(effects
				(font
					(size 1.016 1.016)
					(thickness 0.1524)
				)
				(justify mirror)
			)
		)
		(property "Device Type" "C402H22"
			(at -1.1811 -4.2291 270)
			(unlocked yes)
			(layer "B.Fab")
			(hide yes)
			(effects
				(font
					(size 1.016 1.016)
					(thickness 0.1524)
				)
				(justify mirror)
			)
		)
		(duplicate_pad_numbers_are_jumpers no)
		(fp_rect
			(start 0.4318 0.9525)
			(end -0.4318 -0.9525)
			(stroke
				(width 0)
				(type default)
			)
			(fill no)
			(layer "B.CrtYd")
		)
		(fp_rect
			(start 0.4318 0.9525)
			(end -0.4318 -0.9525)
			(stroke
				(width 0)
				(type default)
			)
			(fill no)
			(layer "B.Fab")
		)
		(pad "1" smd custom
			(at 0 -0.4445 90)
			(size 0.1524 0.1524)
			(layers "B.Cu" "B.Mask" "B.Paste")
			(net "P1V8_C")
			(options
				(clearance outline)
				(anchor circle)
			)
			(primitives
				(gr_poly
					(pts
						(arc
							(start 0.3048 0.2032)
							(mid 0.275042 0.275042)
							(end 0.2032 0.3048)
						)
						(arc
							(start -0.2032 0.3048)
							(mid -0.275042 0.275042)
							(end -0.3048 0.2032)
						)
						(arc
							(start -0.3048 -0.2032)
							(mid -0.275042 -0.275042)
							(end -0.2032 -0.3048)
						)
						(arc
							(start 0.2032 -0.3048)
							(mid 0.275042 -0.275042)
							(end 0.3048 -0.2032)
						)
					)
					(width 0)
					(fill yes)
				)
			)
		)
		(pad "2" smd custom
			(at 0 0.4445 90)
			(size 0.1524 0.1524)
			(layers "B.Cu" "B.Mask" "B.Paste")
			(net "GND")
			(options
				(clearance outline)
				(anchor circle)
			)
			(primitives
				(gr_poly
					(pts
						(arc
							(start 0.3048 0.2032)
							(mid 0.275042 0.275042)
							(end 0.2032 0.3048)
						)
						(arc
							(start -0.2032 0.3048)
							(mid -0.275042 0.275042)
							(end -0.3048 0.2032)
						)
						(arc
							(start -0.3048 -0.2032)
							(mid -0.275042 -0.275042)
							(end -0.2032 -0.3048)
						)
						(arc
							(start 0.2032 -0.3048)
							(mid 0.275042 -0.275042)
							(end 0.3048 -0.2032)
						)
					)
					(width 0)
					(fill yes)
				)
			)
		)
	)
	(footprint ""
		(layer "B.Cu")
		(at 103.505 -60.5028)
		(property "Reference" "C155"
			(at 0 0 0)
			(layer "B.SilkS")
			(hide yes)
			(effects
				(font
					(size 1.27 1.27)
				)
				(justify mirror)
			)
		)
		(property "Value" "SCD1U6D3V1KX-GP"
			(at 2.8321 -1.7399 0)
			(unlocked yes)
			(layer "B.Fab")
			(hide yes)
			(effects
				(font
					(size 1.016 1.016)
					(thickness 0.1524)
				)
				(justify mirror)
			)
		)
		(property "Device Type" "C0201H13"
			(at 2.8321 -3.2639 0)
			(unlocked yes)
			(layer "B.Fab")
			(hide yes)
			(effects
				(font
					(size 1.016 1.016)
					(thickness 0.1524)
				)
				(justify mirror)
			)
		)
		(duplicate_pad_numbers_are_jumpers no)
		(fp_rect
			(start 0.2794 0.6477)
			(end -0.2794 -0.6477)
			(stroke
				(width 0)
				(type default)
			)
			(fill no)
			(layer "B.CrtYd")
		)
		(fp_rect
			(start 0.2794 0.6477)
			(end -0.2794 -0.6477)
			(stroke
				(width 0)
				(type default)
			)
			(fill no)
			(layer "B.Fab")
		)
		(pad "1" smd custom
			(at 0 -0.2794 180)
			(size 0.0762 0.0762)
			(layers "B.Cu" "B.Mask" "B.Paste")
			(net "P1V8_E")
			(options
				(clearance outline)
				(anchor circle)
			)
			(primitives
				(gr_poly
					(pts
						(arc
							(start 0.1524 0.127)
							(mid 0.137521 0.162921)
							(end 0.1016 0.1778)
						)
						(arc
							(start -0.1016 0.1778)
							(mid -0.137521 0.162921)
							(end -0.1524 0.127)
						)
						(arc
							(start -0.1524 -0.127)
							(mid -0.137521 -0.162921)
							(end -0.1016 -0.1778)
						)
						(arc
							(start 0.1016 -0.1778)
							(mid 0.137521 -0.162921)
							(end 0.1524 -0.127)
						)
					)
					(width 0)
					(fill yes)
				)
			)
		)
		(pad "2" smd custom
			(at 0 0.2794 180)
			(size 0.0762 0.0762)
			(layers "B.Cu" "B.Mask" "B.Paste")
			(net "GND")
			(options
				(clearance outline)
				(anchor circle)
			)
			(primitives
				(gr_poly
					(pts
						(arc
							(start 0.1524 0.127)
							(mid 0.137521 0.162921)
							(end 0.1016 0.1778)
						)
						(arc
							(start -0.1016 0.1778)
							(mid -0.137521 0.162921)
							(end -0.1524 0.127)
						)
						(arc
							(start -0.1524 -0.127)
							(mid -0.137521 -0.162921)
							(end -0.1016 -0.1778)
						)
						(arc
							(start 0.1016 -0.1778)
							(mid 0.137521 -0.162921)
							(end 0.1524 -0.127)
						)
					)
					(width 0)
					(fill yes)
				)
			)
		)
	)
	(footprint ""
		(layer "B.Cu")
		(at 76.327 -35.941)
		(property "Reference" "C228"
			(at 0 0 0)
			(layer "B.SilkS")
			(hide yes)
			(effects
				(font
					(size 1.27 1.27)
				)
				(justify mirror)
			)
		)
		(property "Value" "SC22U6D3V3MX-9-GP-U"
			(at 0 -2.8194 0)
			(unlocked yes)
			(layer "B.Fab")
			(hide yes)
			(effects
				(font
					(size 1.016 1.016)
					(thickness 0.1524)
				)
				(justify mirror)
			)
		)
		(property "Device Type" "C603H40"
			(at 0 -4.3434 0)
			(unlocked yes)
			(layer "B.Fab")
			(hide yes)
			(effects
				(font
					(size 1.016 1.016)
					(thickness 0.1524)
				)
				(justify mirror)
			)
		)
		(duplicate_pad_numbers_are_jumpers no)
		(fp_line
			(start -0.508 0)
			(end 0.508 0)
			(stroke
				(width 0.2032)
				(type default)
			)
			(layer "B.SilkS")
		)
		(fp_rect
			(start 0.5842 1.3335)
			(end -0.5842 -1.3335)
			(stroke
				(width 0)
				(type default)
			)
			(fill no)
			(layer "B.CrtYd")
		)
		(fp_rect
			(start 0.5842 1.3335)
			(end -0.5842 -1.3335)
			(stroke
				(width 0)
				(type default)
			)
			(fill no)
			(layer "B.Fab")
		)
		(pad "1" smd custom
			(at 0 -0.762 180)
			(size 0.2159 0.2159)
			(layers "B.Cu" "B.Mask" "B.Paste")
			(net "GB_VDDA")
			(options
				(clearance outline)
				(anchor circle)
			)
			(primitives
				(gr_poly
					(pts
						(arc
							(start -0.3302 0.4318)
							(mid -0.402042 0.402042)
							(end -0.4318 0.3302)
						)
						(arc
							(start -0.4318 -0.3302)
							(mid -0.402042 -0.402042)
							(end -0.3302 -0.4318)
						)
						(arc
							(start 0.3302 -0.4318)
							(mid 0.402042 -0.402042)
							(end 0.4318 -0.3302)
						)
						(arc
							(start 0.4318 0.3302)
							(mid 0.402042 0.402042)
							(end 0.3302 0.4318)
						)
					)
					(width 0)
					(fill yes)
				)
			)
		)
		(pad "2" smd custom
			(at 0 0.762 180)
			(size 0.2159 0.2159)
			(layers "B.Cu" "B.Mask" "B.Paste")
			(net "GND")
			(options
				(clearance outline)
				(anchor circle)
			)
			(primitives
				(gr_poly
					(pts
						(arc
							(start -0.3302 0.4318)
							(mid -0.402042 0.402042)
							(end -0.4318 0.3302)
						)
						(arc
							(start -0.4318 -0.3302)
							(mid -0.402042 -0.402042)
							(end -0.3302 -0.4318)
						)
						(arc
							(start 0.3302 -0.4318)
							(mid 0.402042 -0.402042)
							(end 0.4318 -0.3302)
						)
						(arc
							(start 0.4318 0.3302)
							(mid 0.402042 0.402042)
							(end 0.3302 0.4318)
						)
					)
					(width 0)
					(fill yes)
				)
			)
		)
	)
	(footprint ""
		(layer "B.Cu")
		(at 86.4616 -70.55358 -90)
		(property "Reference" "C517"
			(at 0 0 90)
			(layer "B.SilkS")
			(hide yes)
			(effects
				(font
					(size 1.27 1.27)
				)
				(justify mirror)
			)
		)
		(property "Value" "SCD1U16V2KX-3GP"
			(at -1.1811 -2.7051 270)
			(unlocked yes)
			(layer "B.Fab")
			(hide yes)
			(effects
				(font
					(size 1.016 1.016)
					(thickness 0.1524)
				)
				(justify mirror)
			)
		)
		(property "Device Type" "C402H22"
			(at -1.1811 -4.2291 270)
			(unlocked yes)
			(layer "B.Fab")
			(hide yes)
			(effects
				(font
					(size 1.016 1.016)
					(thickness 0.1524)
				)
				(justify mirror)
			)
		)
		(duplicate_pad_numbers_are_jumpers no)
		(fp_rect
			(start 0.4318 0.9525)
			(end -0.4318 -0.9525)
			(stroke
				(width 0)
				(type default)
			)
			(fill no)
			(layer "B.CrtYd")
		)
		(fp_rect
			(start 0.4318 0.9525)
			(end -0.4318 -0.9525)
			(stroke
				(width 0)
				(type default)
			)
			(fill no)
			(layer "B.Fab")
		)
		(pad "1" smd custom
			(at 0 -0.4445 90)
			(size 0.1524 0.1524)
			(layers "B.Cu" "B.Mask" "B.Paste")
			(net "P1V8_E")
			(options
				(clearance outline)
				(anchor circle)
			)
			(primitives
				(gr_poly
					(pts
						(arc
							(start 0.3048 0.2032)
							(mid 0.275042 0.275042)
							(end 0.2032 0.3048)
						)
						(arc
							(start -0.2032 0.3048)
							(mid -0.275042 0.275042)
							(end -0.3048 0.2032)
						)
						(arc
							(start -0.3048 -0.2032)
							(mid -0.275042 -0.275042)
							(end -0.2032 -0.3048)
						)
						(arc
							(start 0.2032 -0.3048)
							(mid 0.275042 -0.275042)
							(end 0.3048 -0.2032)
						)
					)
					(width 0)
					(fill yes)
				)
			)
		)
		(pad "2" smd custom
			(at 0 0.4445 90)
			(size 0.1524 0.1524)
			(layers "B.Cu" "B.Mask" "B.Paste")
			(net "GND")
			(options
				(clearance outline)
				(anchor circle)
			)
			(primitives
				(gr_poly
					(pts
						(arc
							(start 0.3048 0.2032)
							(mid 0.275042 0.275042)
							(end 0.2032 0.3048)
						)
						(arc
							(start -0.2032 0.3048)
							(mid -0.275042 0.275042)
							(end -0.3048 0.2032)
						)
						(arc
							(start -0.3048 -0.2032)
							(mid -0.275042 -0.275042)
							(end -0.2032 -0.3048)
						)
						(arc
							(start 0.2032 -0.3048)
							(mid 0.275042 -0.275042)
							(end 0.3048 -0.2032)
						)
					)
					(width 0)
					(fill yes)
				)
			)
		)
	)
)
